%#################################################################
Title:        Synonyms Report
Design:       s9s_mb_2u
Date:         Sep 23 11:20:32 2022
%#################################################################


%
Page wise report of nets and their synonyms
%

Page.Scope               	Net Name                       	Synonyms          	Location([Zone][Dir])

